FILE_TYPE = MACRO_DRAWING;
SET COLOR_WIRE YELLOW;
SET COLOR_PROP MONO;
SET COLOR_DOT WHITE;
SET COLOR_ARC YELLOW;
SET COLOR_BODY GREEN;
SET COLOR_NOTE MONO;
SET PROP_DISPLAY VALUE;
SET PAGE_NUMBER P263;
FORCEADD INTEL_CORP_BPAGE..1
(-1375 1600);
FORCEPROP 1 LAST CDS_CON_LAST_MODIFIED Fri Jun 16 17:49:40 2017
J 0
(-2800 1925);
PAINT ORANGE (-2800 1925);
DISPLAY INVISIBLE (-2800 1925);
FORCEPROP 2 LAST CUSTOM_TXT_CDS <XR_PAGE_TITLE>
J 0
(-9265 6850);
DISPLAY 0.638298 (-9265 6850);
PAINT PINK (-9265 6850);
DISPLAY INVISIBLE (-9265 6850);
FORCEPROP 2 LAST CUSTOM_TXT_CDS <CON_LAST_MODIFIED>
J 0
(-5375 1700);
PAINT ORANGE (-5375 1700);
FORCEPROP 2 LAST CUSTOM_TXT_CDS <CURRENT_DESIGN_SHEET> OF <TOTAL_DESIGN_SHEETS>
J 0
(-1875 1625);
PAINT ORANGE (-1875 1625);
FORCEPROP 1 LAST SCH_TITLE XDP BLOCK DIAGRAM
J 0
(-9325 1650);
DISPLAY 2.468085 (-9325 1650);
PAINT ORANGE (-9325 1650);
FORCEPROP 2 LAST CDS_LIB mstr_symbols
J 0
(-1375 1600);
PAINT MONO (-1375 1600);
DISPLAY INVISIBLE (-1375 1600);
FORCEPROP 2 LAST PAGE_BORDER TRUE
J 0
(-9265 6850);
DISPLAY 0.638298 (-9265 6850);
PAINT PINK (-9265 6850);
DISPLAY INVISIBLE (-9265 6850);
FORCEPROP 1 LAST COMMENT_BODY TRUE
J 0
(-1363 1612);
DISPLAY 0.468085 (-1363 1612);
PAINT GREEN (-1363 1612);
DISPLAY INVISIBLE (-1363 1612);
FORCEPROP 2 LAST CDS_XR_PAGE_TITLE CR-267 : @BASEBOARD_FAB2_LIB.BASEBOARD_FAB2(SCH_1):PAGE267
J 0
(-9265 6850);
DISPLAY 0.638298 (-9265 6850);
PAINT PINK (-9265 6850);
DISPLAY INVISIBLE (-9265 6850);
FORCENOTE
$CDS_IMAGE|XDP Block diagram_20161011.jpg|8300|5750
(-5375 4075) 0;
DISPLAY LEFT (-5375 4075);
QUIT
